# Stackup_F0T_PDB_GPU_10L_2p36mm_IT-170GT_RTF_Rev0p2_20211201.xls — Vendor Stackup (pcb-stackup)
| STACKUP |  |  |  | Target Z (ohms) - MicroStrip |  |  |  |  |  |  |  | 50 |  |  | Breakout |
|  |  |  |  | Target Z (ohms) - StripLine |  |  |  |  |  |  |  | 50 |  |  |  |
|  |  |  |  | Z tolerance |  |  |  |  |  |  |  | 0.1 |  |  |  |
|  |  |  |  | Z Type |  |  |  |  |  |  |  | Single |  |  | Single |
| Layer# | Material | Description |  | Copper Weight (oz) | Thickness (mil) | Tolerance (mil) | Glass Fabric | Er | Vendor Thickness (mil) | Vendor Glass Fabric | Vendor Er | Width | Vendor Width | Vendor Impedance | Width |
|  |  |  | Soldermask |  | 0.6 |  |  | 3.8 |  |  |  |  |  |  |  |
| 1 |  |  | TOP | 0.5+plating | 1.95 |  |  |  |  |  |  | 6.8 |  |  | 4 |
|  | IT-170GT |  | PP |  | 4 | ±0.709 | 106x2 | 3.87 |  |  |  |  |  |  |  |
| 2 |  |  | GND | 2 (RTF) | 2.6 |  |  |  |  |  |  |  |  |  |  |
|  | IT-170GT |  | CORE |  | 6 | ±0.984 | 1080x2 | 3.89 |  |  |  |  |  |  |  |
| 3 |  |  | IN1 | 1 (RTF) | 1.3 |  |  |  |  |  |  | 5.1 |  |  | 4 |
|  | IT-170GT |  | PP |  | 6 | ±0.984 | 3313x1+1078x1 | 3.89 |  |  |  |  |  |  |  |
| 4 |  |  | GND1 | 2 (RTF) | 2.6 |  |  |  |  |  |  |  |  |  |  |
|  | IT-170GT |  | CORE |  | 6 | ±0.984 | 1080x2 | 3.89 |  |  |  |  |  |  |  |
| 5 |  |  | VCC | 2 (RTF) | 2.6 |  |  |  |  |  |  |  |  |  |  |
|  | IT-170GT |  | PP |  | 25.6 | ±2.52 | Vendor Define | 4.08 |  |  |  |  |  |  |  |
| 6 |  |  | VCC1 | 2 (RTF) | 2.6 |  |  |  |  |  |  |  |  |  |  |
|  | IT-170GT |  | CORE |  | 6 | ±0.984 | 1080x2 | 3.89 |  |  |  |  |  |  |  |
| 7 |  |  | GND2 | 2 (RTF) | 2.6 |  |  |  |  |  |  |  |  |  |  |
|  | IT-170GT |  | PP |  | 6 | ±0.984 | 3313x1+1078x1 | 3.89 |  |  |  |  |  |  |  |
| 8 |  |  | IN2 | 1 (RTF) | 1.3 |  |  |  |  |  |  | 5.1 |  |  | 4 |
|  | IT-170GT |  | CORE |  | 6 | ±0.984 | 1080x2 | 3.89 |  |  |  |  |  |  |  |
| 9 |  |  | GND3 | 2 (RTF) | 2.6 |  |  |  |  |  |  |  |  |  |  |
|  | IT-170GT |  | PP |  | 4 | ±0.709 | 106x2 | 3.87 |  |  |  |  |  |  |  |
| 10 |  |  | BOTTOM | 0.5+plating | 1.95 |  |  |  |  |  |  | 6.8 |  |  | 4 |
|  |  |  | Soldermask |  | 0.6 |  |  | 3.8 |  |  |  |  |  |  |  |
|  |  |  |  | Total | 92.89999999999998 | ±10% |  |  | 0 |  |  |  |  |  |  |
